(kicad_pcb
	(version 20260206)
	(generator "pcbnew")
	(generator_version "10.0")
	(general
		(thickness 1.6)
		(legacy_teardrops no)
	)
	(paper "A4")
	(title_block
		(title "03242023_DA0F0TMBIJ0_F0T_Motherboard_J_brd_V01_OCP.brd")
		(comment 1 "Grand Teton / footprints 1535-1540 of 6105")
	)
	(layers
		(0 "F.Cu" signal "TOP")
		(4 "In1.Cu" signal "GND")
		(6 "In2.Cu" signal "IN1")
		(8 "In3.Cu" signal "GND1")
		(10 "In4.Cu" signal "IN2")
		(12 "In5.Cu" signal "GND2")
		(14 "In6.Cu" signal "IN3")
		(16 "In7.Cu" signal "GND3")
		(18 "In8.Cu" signal "VCC")
		(20 "In9.Cu" signal "VCC1")
		(22 "In10.Cu" signal "GND4")
		(24 "In11.Cu" signal "IN4")
		(26 "In12.Cu" signal "GND5")
		(28 "In13.Cu" signal "IN5")
		(30 "In14.Cu" signal "GND6")
		(32 "In15.Cu" signal "IN6")
		(34 "In16.Cu" signal "GND7")
		(2 "B.Cu" signal "BOTTOM")
		(9 "F.Adhes" user "F.Adhesive")
		(11 "B.Adhes" user "B.Adhesive")
		(13 "F.Paste" user "Package Geometry/Pastemask Top")
		(15 "B.Paste" user "Package Geometry/Pastemask Bottom")
		(5 "F.SilkS" user "Ref Des/Silkscreen Top")
		(7 "B.SilkS" user "Ref Des/Silkscreen Bottom")
		(1 "F.Mask" user "Board Geometry/Soldermask Top")
		(3 "B.Mask" user "Board Geometry/Soldermask Bottom")
		(17 "Dwgs.User" user "User.Drawings")
		(19 "Cmts.User" user "User.Comments")
		(21 "Eco1.User" user "User.Eco1")
		(23 "Eco2.User" user "User.Eco2")
		(25 "Edge.Cuts" user "Board Geometry/Outline")
		(27 "Margin" user)
		(31 "F.CrtYd" user "Package Geometry/Place Bound Top")
		(29 "B.CrtYd" user "Package Geometry/Place Bound Bottom")
		(35 "F.Fab" user "Ref Des/Assembly Top")
		(33 "B.Fab" user "Ref Des/Assembly Bottom")
	)
	(footprint ""
		(layer "F.Cu")
		(at 179.12588 -133.695948 -90)
		(property "Reference" "R1448"
			(at 0 0 270)
			(layer "F.SilkS")
			(hide yes)
			(effects
				(font
					(size 1.27 1.27)
				)
			)
		)
		(property "Value" ""
			(at 0 0 270)
			(layer "F.Fab")
			(effects
				(font
					(size 1.27 1.27)
				)
			)
		)
		(duplicate_pad_numbers_are_jumpers no)
		(fp_line
			(start -0.7874 0.4064)
			(end -0.7874 -0.4064)
			(stroke
				(width 0.1524)
				(type default)
			)
			(layer "F.SilkS")
		)
		(fp_line
			(start 0.7874 0.4064)
			(end -0.7874 0.4064)
			(stroke
				(width 0.1524)
				(type default)
			)
			(layer "F.SilkS")
		)
		(fp_line
			(start -0.7874 -0.4064)
			(end 0.7874 -0.4064)
			(stroke
				(width 0.1524)
				(type default)
			)
			(layer "F.SilkS")
		)
		(fp_line
			(start 0.7874 -0.4064)
			(end 0.7874 0.4064)
			(stroke
				(width 0.1524)
				(type default)
			)
			(layer "F.SilkS")
		)
		(fp_line
			(start -0.67945 0.3048)
			(end -0.67945 -0.305054)
			(stroke
				(width 0.1)
				(type default)
			)
			(layer "F.Fab")
		)
		(fp_line
			(start -0.12065 0.3048)
			(end -0.67945 0.3048)
			(stroke
				(width 0.1)
				(type default)
			)
			(layer "F.Fab")
		)
		(fp_line
			(start 0.120396 0.3048)
			(end 0.120396 0.2794)
			(stroke
				(width 0.1)
				(type default)
			)
			(layer "F.Fab")
		)
		(fp_line
			(start 0.67945 0.3048)
			(end 0.120396 0.3048)
			(stroke
				(width 0.1)
				(type default)
			)
			(layer "F.Fab")
		)
		(fp_line
			(start -0.12065 0.2794)
			(end -0.12065 0.3048)
			(stroke
				(width 0.1)
				(type default)
			)
			(layer "F.Fab")
		)
		(fp_line
			(start 0.120396 0.2794)
			(end -0.12065 0.2794)
			(stroke
				(width 0.1)
				(type default)
			)
			(layer "F.Fab")
		)
		(fp_line
			(start -0.12065 -0.2794)
			(end 0.12065 -0.2794)
			(stroke
				(width 0.1)
				(type default)
			)
			(layer "F.Fab")
		)
		(fp_line
			(start 0.12065 -0.2794)
			(end 0.12065 -0.3048)
			(stroke
				(width 0.1)
				(type default)
			)
			(layer "F.Fab")
		)
		(fp_line
			(start 0.12065 -0.3048)
			(end 0.67945 -0.3048)
			(stroke
				(width 0.1)
				(type default)
			)
			(layer "F.Fab")
		)
		(fp_line
			(start 0.67945 -0.3048)
			(end 0.67945 0.3048)
			(stroke
				(width 0.1)
				(type default)
			)
			(layer "F.Fab")
		)
		(fp_line
			(start -0.67945 -0.305054)
			(end -0.12065 -0.305054)
			(stroke
				(width 0.1)
				(type default)
			)
			(layer "F.Fab")
		)
		(fp_line
			(start -0.12065 -0.305054)
			(end -0.12065 -0.2794)
			(stroke
				(width 0.1)
				(type default)
			)
			(layer "F.Fab")
		)
		(pad "1" smd circle
			(at -0.40005 0 270)
			(size 0 0)
			(layers "F.Cu" "F.Mask" "F.Paste")
			(net "FM_CPU1_SKTOCC_LVT3_N")
		)
		(pad "2" smd circle
			(at 0.40005 0 270)
			(size 0 0)
			(layers "F.Cu" "F.Mask" "F.Paste")
			(net "FM_CPU1_SKTOCC_LVT3_PLD_N")
		)
	)
	(footprint ""
		(layer "F.Cu")
		(at 298.16552 -407.6954)
		(property "Reference" "R4684"
			(at 0 0 0)
			(layer "F.SilkS")
			(hide yes)
			(effects
				(font
					(size 1.27 1.27)
				)
			)
		)
		(property "Value" ""
			(at 0 0 0)
			(layer "F.Fab")
			(effects
				(font
					(size 1.27 1.27)
				)
			)
		)
		(duplicate_pad_numbers_are_jumpers no)
		(fp_line
			(start -0.7874 -0.4064)
			(end 0.7874 -0.4064)
			(stroke
				(width 0.1524)
				(type default)
			)
			(layer "F.SilkS")
		)
		(fp_line
			(start -0.7874 0.4064)
			(end -0.7874 -0.4064)
			(stroke
				(width 0.1524)
				(type default)
			)
			(layer "F.SilkS")
		)
		(fp_line
			(start 0.7874 -0.4064)
			(end 0.7874 0.4064)
			(stroke
				(width 0.1524)
				(type default)
			)
			(layer "F.SilkS")
		)
		(fp_line
			(start 0.7874 0.4064)
			(end -0.7874 0.4064)
			(stroke
				(width 0.1524)
				(type default)
			)
			(layer "F.SilkS")
		)
		(fp_line
			(start -0.67945 -0.305054)
			(end -0.12065 -0.305054)
			(stroke
				(width 0.1)
				(type default)
			)
			(layer "F.Fab")
		)
		(fp_line
			(start -0.67945 0.3048)
			(end -0.67945 -0.305054)
			(stroke
				(width 0.1)
				(type default)
			)
			(layer "F.Fab")
		)
		(fp_line
			(start -0.12065 -0.305054)
			(end -0.12065 -0.2794)
			(stroke
				(width 0.1)
				(type default)
			)
			(layer "F.Fab")
		)
		(fp_line
			(start -0.12065 -0.2794)
			(end 0.12065 -0.2794)
			(stroke
				(width 0.1)
				(type default)
			)
			(layer "F.Fab")
		)
		(fp_line
			(start -0.12065 0.2794)
			(end -0.12065 0.3048)
			(stroke
				(width 0.1)
				(type default)
			)
			(layer "F.Fab")
		)
		(fp_line
			(start -0.12065 0.3048)
			(end -0.67945 0.3048)
			(stroke
				(width 0.1)
				(type default)
			)
			(layer "F.Fab")
		)
		(fp_line
			(start 0.120396 0.2794)
			(end -0.12065 0.2794)
			(stroke
				(width 0.1)
				(type default)
			)
			(layer "F.Fab")
		)
		(fp_line
			(start 0.120396 0.3048)
			(end 0.120396 0.2794)
			(stroke
				(width 0.1)
				(type default)
			)
			(layer "F.Fab")
		)
		(fp_line
			(start 0.12065 -0.3048)
			(end 0.67945 -0.3048)
			(stroke
				(width 0.1)
				(type default)
			)
			(layer "F.Fab")
		)
		(fp_line
			(start 0.12065 -0.2794)
			(end 0.12065 -0.3048)
			(stroke
				(width 0.1)
				(type default)
			)
			(layer "F.Fab")
		)
		(fp_line
			(start 0.67945 -0.3048)
			(end 0.67945 0.3048)
			(stroke
				(width 0.1)
				(type default)
			)
			(layer "F.Fab")
		)
		(fp_line
			(start 0.67945 0.3048)
			(end 0.120396 0.3048)
			(stroke
				(width 0.1)
				(type default)
			)
			(layer "F.Fab")
		)
		(pad "1" smd circle
			(at -0.40005 0)
			(size 0 0)
			(layers "F.Cu" "F.Mask" "F.Paste")
			(net "P12V_HSC_TEMP_ALERT_N")
		)
		(pad "2" smd circle
			(at 0.40005 0)
			(size 0 0)
			(layers "F.Cu" "F.Mask" "F.Paste")
			(net "P12V_HSC_TEMP_ALERT_R_N")
		)
	)
	(footprint ""
		(layer "F.Cu")
		(at 118.542816 -241.97691 -90)
		(property "Reference" "C254"
			(at 0 0 270)
			(layer "F.SilkS")
			(hide yes)
			(effects
				(font
					(size 1.27 1.27)
				)
			)
		)
		(property "Value" ""
			(at 0 0 270)
			(layer "F.Fab")
			(effects
				(font
					(size 1.27 1.27)
				)
			)
		)
		(duplicate_pad_numbers_are_jumpers no)
		(fp_line
			(start -0.7874 0.4064)
			(end -0.7874 -0.4064)
			(stroke
				(width 0.1524)
				(type default)
			)
			(layer "F.SilkS")
		)
		(fp_line
			(start 0.7874 0.4064)
			(end -0.7874 0.4064)
			(stroke
				(width 0.1524)
				(type default)
			)
			(layer "F.SilkS")
		)
		(fp_line
			(start -0.7874 -0.4064)
			(end 0.7874 -0.4064)
			(stroke
				(width 0.1524)
				(type default)
			)
			(layer "F.SilkS")
		)
		(fp_line
			(start 0.7874 -0.4064)
			(end 0.7874 0.4064)
			(stroke
				(width 0.1524)
				(type default)
			)
			(layer "F.SilkS")
		)
		(fp_line
			(start -0.67945 0.3048)
			(end -0.67945 -0.305054)
			(stroke
				(width 0.1)
				(type default)
			)
			(layer "F.Fab")
		)
		(fp_line
			(start -0.12065 0.3048)
			(end -0.67945 0.3048)
			(stroke
				(width 0.1)
				(type default)
			)
			(layer "F.Fab")
		)
		(fp_line
			(start 0.120396 0.3048)
			(end 0.120396 0.2794)
			(stroke
				(width 0.1)
				(type default)
			)
			(layer "F.Fab")
		)
		(fp_line
			(start 0.67945 0.3048)
			(end 0.120396 0.3048)
			(stroke
				(width 0.1)
				(type default)
			)
			(layer "F.Fab")
		)
		(fp_line
			(start -0.12065 0.2794)
			(end -0.12065 0.3048)
			(stroke
				(width 0.1)
				(type default)
			)
			(layer "F.Fab")
		)
		(fp_line
			(start 0.120396 0.2794)
			(end -0.12065 0.2794)
			(stroke
				(width 0.1)
				(type default)
			)
			(layer "F.Fab")
		)
		(fp_line
			(start -0.12065 -0.2794)
			(end 0.12065 -0.2794)
			(stroke
				(width 0.1)
				(type default)
			)
			(layer "F.Fab")
		)
		(fp_line
			(start 0.12065 -0.2794)
			(end 0.12065 -0.3048)
			(stroke
				(width 0.1)
				(type default)
			)
			(layer "F.Fab")
		)
		(fp_line
			(start 0.12065 -0.3048)
			(end 0.67945 -0.3048)
			(stroke
				(width 0.1)
				(type default)
			)
			(layer "F.Fab")
		)
		(fp_line
			(start 0.67945 -0.3048)
			(end 0.67945 0.3048)
			(stroke
				(width 0.1)
				(type default)
			)
			(layer "F.Fab")
		)
		(fp_line
			(start -0.67945 -0.305054)
			(end -0.12065 -0.305054)
			(stroke
				(width 0.1)
				(type default)
			)
			(layer "F.Fab")
		)
		(fp_line
			(start -0.12065 -0.305054)
			(end -0.12065 -0.2794)
			(stroke
				(width 0.1)
				(type default)
			)
			(layer "F.Fab")
		)
		(pad "1" smd circle
			(at -0.40005 0 270)
			(size 0 0)
			(layers "F.Cu" "F.Mask" "F.Paste")
			(net "PVCCIN_CPU1")
		)
		(pad "2" smd circle
			(at 0.40005 0 270)
			(size 0 0)
			(layers "F.Cu" "F.Mask" "F.Paste")
			(net "GND")
		)
	)
	(footprint ""
		(layer "F.Cu")
		(at 420.124128 -166.499286 -90)
		(property "Reference" "PC191_P0_1"
			(at 0 0 270)
			(layer "F.SilkS")
			(hide yes)
			(effects
				(font
					(size 1.27 1.27)
				)
			)
		)
		(property "Value" ""
			(at 0 0 270)
			(layer "F.Fab")
			(effects
				(font
					(size 1.27 1.27)
				)
			)
		)
		(duplicate_pad_numbers_are_jumpers no)
		(fp_line
			(start -0.7874 0.4064)
			(end -0.7874 -0.4064)
			(stroke
				(width 0.1524)
				(type default)
			)
			(layer "F.SilkS")
		)
		(fp_line
			(start 0.7874 0.4064)
			(end -0.7874 0.4064)
			(stroke
				(width 0.1524)
				(type default)
			)
			(layer "F.SilkS")
		)
		(fp_line
			(start -0.7874 -0.4064)
			(end 0.7874 -0.4064)
			(stroke
				(width 0.1524)
				(type default)
			)
			(layer "F.SilkS")
		)
		(fp_line
			(start 0.7874 -0.4064)
			(end 0.7874 0.4064)
			(stroke
				(width 0.1524)
				(type default)
			)
			(layer "F.SilkS")
		)
		(fp_line
			(start -0.67945 0.3048)
			(end -0.67945 -0.305054)
			(stroke
				(width 0.1)
				(type default)
			)
			(layer "F.Fab")
		)
		(fp_line
			(start -0.12065 0.3048)
			(end -0.67945 0.3048)
			(stroke
				(width 0.1)
				(type default)
			)
			(layer "F.Fab")
		)
		(fp_line
			(start 0.120396 0.3048)
			(end 0.120396 0.2794)
			(stroke
				(width 0.1)
				(type default)
			)
			(layer "F.Fab")
		)
		(fp_line
			(start 0.67945 0.3048)
			(end 0.120396 0.3048)
			(stroke
				(width 0.1)
				(type default)
			)
			(layer "F.Fab")
		)
		(fp_line
			(start -0.12065 0.2794)
			(end -0.12065 0.3048)
			(stroke
				(width 0.1)
				(type default)
			)
			(layer "F.Fab")
		)
		(fp_line
			(start 0.120396 0.2794)
			(end -0.12065 0.2794)
			(stroke
				(width 0.1)
				(type default)
			)
			(layer "F.Fab")
		)
		(fp_line
			(start -0.12065 -0.2794)
			(end 0.12065 -0.2794)
			(stroke
				(width 0.1)
				(type default)
			)
			(layer "F.Fab")
		)
		(fp_line
			(start 0.12065 -0.2794)
			(end 0.12065 -0.3048)
			(stroke
				(width 0.1)
				(type default)
			)
			(layer "F.Fab")
		)
		(fp_line
			(start 0.12065 -0.3048)
			(end 0.67945 -0.3048)
			(stroke
				(width 0.1)
				(type default)
			)
			(layer "F.Fab")
		)
		(fp_line
			(start 0.67945 -0.3048)
			(end 0.67945 0.3048)
			(stroke
				(width 0.1)
				(type default)
			)
			(layer "F.Fab")
		)
		(fp_line
			(start -0.67945 -0.305054)
			(end -0.12065 -0.305054)
			(stroke
				(width 0.1)
				(type default)
			)
			(layer "F.Fab")
		)
		(fp_line
			(start -0.12065 -0.305054)
			(end -0.12065 -0.2794)
			(stroke
				(width 0.1)
				(type default)
			)
			(layer "F.Fab")
		)
		(pad "1" smd circle
			(at -0.40005 0 270)
			(size 0 0)
			(layers "F.Cu" "F.Mask" "F.Paste")
			(net "SW_P12V_PVCCINFAON_CPU0_FLT")
		)
		(pad "2" smd circle
			(at 0.40005 0 270)
			(size 0 0)
			(layers "F.Cu" "F.Mask" "F.Paste")
			(net "GND")
		)
	)
	(footprint ""
		(layer "F.Cu")
		(at 103.85552 -31.731458 180)
		(property "Reference" "U235"
			(at 1.59766 -2.717292 0)
			(unlocked yes)
			(layer "F.SilkS")
			(effects
				(font
					(size 0.7874 0.5842)
					(thickness 0.1524)
				)
				(justify left)
			)
		)
		(property "Value" ""
			(at 0 0 180)
			(layer "F.Fab")
			(effects
				(font
					(size 1.27 1.27)
				)
			)
		)
		(duplicate_pad_numbers_are_jumpers no)
		(fp_line
			(start 1.463548 1.549908)
			(end -1.463548 1.549908)
			(stroke
				(width 0.1524)
				(type default)
			)
			(layer "F.SilkS")
		)
		(fp_line
			(start 1.463548 -1.549908)
			(end 1.463548 1.549908)
			(stroke
				(width 0.1524)
				(type default)
			)
			(layer "F.SilkS")
		)
		(fp_line
			(start 0.762 -1.549908)
			(end 1.463548 -1.549908)
			(stroke
				(width 0.1524)
				(type default)
			)
			(layer "F.SilkS")
		)
		(fp_line
			(start 0 -0.762)
			(end 0.762 -1.549908)
			(stroke
				(width 0.1524)
				(type default)
			)
			(layer "F.SilkS")
		)
		(fp_line
			(start -0.787908 -1.549908)
			(end 0 -0.762)
			(stroke
				(width 0.1524)
				(type default)
			)
			(layer "F.SilkS")
		)
		(fp_line
			(start -1.463548 1.549908)
			(end -1.463548 -1.549908)
			(stroke
				(width 0.1524)
				(type default)
			)
			(layer "F.SilkS")
		)
		(fp_line
			(start -1.463548 -1.549908)
			(end -0.787908 -1.549908)
			(stroke
				(width 0.1524)
				(type default)
			)
			(layer "F.SilkS")
		)
		(fp_poly
			(pts
				(xy -2.84988 -1.050036) (xy -3.46964 -0.740156) (xy -3.46964 -1.359916)
			)
			(stroke
				(width 0)
				(type default)
			)
			(fill yes)
			(layer "F.SilkS")
		)
		(fp_line
			(start 1.549908 1.549908)
			(end -1.549908 1.549908)
			(stroke
				(width 0.1)
				(type default)
			)
			(layer "F.Fab")
		)
		(fp_line
			(start 1.549908 -1.549908)
			(end 1.549908 1.549908)
			(stroke
				(width 0.1)
				(type default)
			)
			(layer "F.Fab")
		)
		(fp_line
			(start -1.549908 1.549908)
			(end -1.549908 -1.549908)
			(stroke
				(width 0.1)
				(type default)
			)
			(layer "F.Fab")
		)
		(fp_line
			(start -1.549908 -1.549908)
			(end 1.549908 -1.549908)
			(stroke
				(width 0.1)
				(type default)
			)
			(layer "F.Fab")
		)
		(fp_poly
			(pts
				(xy -3.4798 -1.359916) (xy -2.86004 -1.050036) (xy -3.4798 -0.740156)
			)
			(stroke
				(width 0)
				(type default)
			)
			(fill yes)
			(layer "F.Fab")
		)
		(pad "1" smd rect
			(at -2.175002 -1.050036 270)
			(size 0.6096 1.1684)
			(layers "F.Cu" "F.Mask" "F.Paste")
			(net "P3V3_AUX")
		)
		(pad "2" smd rect
			(at -2.175002 -0.32512 270)
			(size 0.4318 1.1684)
			(layers "F.Cu" "F.Mask" "F.Paste")
			(net "SMB_OCP_V3_2_3V3AUX_SCL")
		)
		(pad "3" smd rect
			(at -2.175002 0.32512 270)
			(size 0.4318 1.1684)
			(layers "F.Cu" "F.Mask" "F.Paste")
			(net "SMB_OCP_V3_2_3V3AUX_SDA")
		)
		(pad "4" smd rect
			(at -2.175002 1.050036 270)
			(size 0.6096 1.1684)
			(layers "F.Cu" "F.Mask" "F.Paste")
			(net "GND")
		)
		(pad "5" smd rect
			(at 2.175002 1.050036 270)
			(size 0.6096 1.1684)
			(layers "F.Cu" "F.Mask" "F.Paste")
			(net "HP_LVC3_OCP_V3_2_R_EN")
		)
		(pad "6" smd rect
			(at 2.175002 0.32512 270)
			(size 0.4318 1.1684)
			(layers "F.Cu" "F.Mask" "F.Paste")
			(net "SMB_OCP_V3_2_3V3AUX_BUF_SDA")
		)
		(pad "7" smd rect
			(at 2.175002 -0.32512 270)
			(size 0.4318 1.1684)
			(layers "F.Cu" "F.Mask" "F.Paste")
			(net "SMB_OCP_V3_2_3V3AUX_BUF_SCL")
		)
		(pad "8" smd rect
			(at 2.175002 -1.050036 270)
			(size 0.6096 1.1684)
			(layers "F.Cu" "F.Mask" "F.Paste")
			(net "P3V3_OCP_V3_2")
		)
	)
	(footprint ""
		(layer "F.Cu")
		(at 160.261554 -31.341568 90)
		(property "Reference" "R4462"
			(at 0 0 90)
			(layer "F.SilkS")
			(hide yes)
			(effects
				(font
					(size 1.27 1.27)
				)
			)
		)
		(property "Value" ""
			(at 0 0 90)
			(layer "F.Fab")
			(effects
				(font
					(size 1.27 1.27)
				)
			)
		)
		(duplicate_pad_numbers_are_jumpers no)
		(fp_line
			(start 0.7874 -0.4064)
			(end 0.7874 0.4064)
			(stroke
				(width 0.1524)
				(type default)
			)
			(layer "F.SilkS")
		)
		(fp_line
			(start -0.7874 -0.4064)
			(end 0.7874 -0.4064)
			(stroke
				(width 0.1524)
				(type default)
			)
			(layer "F.SilkS")
		)
		(fp_line
			(start 0.7874 0.4064)
			(end -0.7874 0.4064)
			(stroke
				(width 0.1524)
				(type default)
			)
			(layer "F.SilkS")
		)
		(fp_line
			(start -0.7874 0.4064)
			(end -0.7874 -0.4064)
			(stroke
				(width 0.1524)
				(type default)
			)
			(layer "F.SilkS")
		)
		(fp_line
			(start -0.12065 -0.305054)
			(end -0.12065 -0.2794)
			(stroke
				(width 0.1)
				(type default)
			)
			(layer "F.Fab")
		)
		(fp_line
			(start -0.67945 -0.305054)
			(end -0.12065 -0.305054)
			(stroke
				(width 0.1)
				(type default)
			)
			(layer "F.Fab")
		)
		(fp_line
			(start 0.67945 -0.3048)
			(end 0.67945 0.3048)
			(stroke
				(width 0.1)
				(type default)
			)
			(layer "F.Fab")
		)
		(fp_line
			(start 0.12065 -0.3048)
			(end 0.67945 -0.3048)
			(stroke
				(width 0.1)
				(type default)
			)
			(layer "F.Fab")
		)
		(fp_line
			(start 0.12065 -0.2794)
			(end 0.12065 -0.3048)
			(stroke
				(width 0.1)
				(type default)
			)
			(layer "F.Fab")
		)
		(fp_line
			(start -0.12065 -0.2794)
			(end 0.12065 -0.2794)
			(stroke
				(width 0.1)
				(type default)
			)
			(layer "F.Fab")
		)
		(fp_line
			(start 0.120396 0.2794)
			(end -0.12065 0.2794)
			(stroke
				(width 0.1)
				(type default)
			)
			(layer "F.Fab")
		)
		(fp_line
			(start -0.12065 0.2794)
			(end -0.12065 0.3048)
			(stroke
				(width 0.1)
				(type default)
			)
			(layer "F.Fab")
		)
		(fp_line
			(start 0.67945 0.3048)
			(end 0.120396 0.3048)
			(stroke
				(width 0.1)
				(type default)
			)
			(layer "F.Fab")
		)
		(fp_line
			(start 0.120396 0.3048)
			(end 0.120396 0.2794)
			(stroke
				(width 0.1)
				(type default)
			)
			(layer "F.Fab")
		)
		(fp_line
			(start -0.12065 0.3048)
			(end -0.67945 0.3048)
			(stroke
				(width 0.1)
				(type default)
			)
			(layer "F.Fab")
		)
		(fp_line
			(start -0.67945 0.3048)
			(end -0.67945 -0.305054)
			(stroke
				(width 0.1)
				(type default)
			)
			(layer "F.Fab")
		)
		(pad "1" smd circle
			(at -0.40005 0 90)
			(size 0 0)
			(layers "F.Cu" "F.Mask" "F.Paste")
			(net "P3V3_AUX_USB_HUB_2")
		)
		(pad "2" smd circle
			(at 0.40005 0 90)
			(size 0 0)
			(layers "F.Cu" "F.Mask" "F.Paste")
			(net "USB_HUB_2_DVDD")
		)
	)
)
